# BASEBOARD_FAB2 (Tioga Pass) — schematic netlist excerpt (pin names and nets, part order shuffled) for the footprints in the layout excerpt that follows; sources: Cadence DE-HDL packaged netlist, KiCad conversion of Wiwynn_Tioga_Pass_MB.brd

R6W3  232KR2F-2-GP  1%  pkg SMD-RG1  page 200 : \1\ = UV_HIGH_SET_N ; \2\ = A_P12V_STBY_FP_TRIGGER
R25W136  RES  33.2 1% CHIP  pkg 0402  page 252 : A = I2C_BMC_VGA_DDC_SDA_G ; B = V_IBMC_5V_DDC_SDA_J
R7P21  RES  150.0 1% CHIP  pkg 0402  page 152 : A = H_CPU1_MEMKLM_MEMHOT_G_N ; B = PVCCIO_CPU1

(kicad_pcb
	(version 20260206)
	(generator "pcbnew")
	(generator_version "10.0")
	(general
		(thickness 1.6)
		(legacy_teardrops no)
	)
	(paper "A4")
	(title_block
		(title "Wiwynn_Tioga_Pass_MB.brd")
		(comment 1 "Tioga Pass / footprints 3846-3848 of 4770")
	)
	(layers
		(0 "F.Cu" signal "TOP")
		(4 "In1.Cu" signal "L2GND")
		(6 "In2.Cu" signal "L3")
		(8 "In3.Cu" signal "L4GND")
		(10 "In4.Cu" signal "L5")
		(12 "In5.Cu" signal "L6GND")
		(14 "In6.Cu" signal "L7VCC")
		(16 "In7.Cu" signal "L8VCC")
		(18 "In8.Cu" signal "L9GND")
		(20 "In9.Cu" signal "L10")
		(22 "In10.Cu" signal "L11GND")
		(24 "In11.Cu" signal "L12")
		(26 "In12.Cu" signal "L13GND")
		(2 "B.Cu" signal "BOTTOM")
		(9 "F.Adhes" user "F.Adhesive")
		(11 "B.Adhes" user "B.Adhesive")
		(13 "F.Paste" user "Package Geometry/Pastemask Top")
		(15 "B.Paste" user "Package Geometry/Pastemask Bottom")
		(5 "F.SilkS" user "Ref Des/Silkscreen Top")
		(7 "B.SilkS" user "Ref Des/Silkscreen Bottom")
		(1 "F.Mask" user "Board Geometry/Soldermask Top")
		(3 "B.Mask" user "Board Geometry/Soldermask Bottom")
		(17 "Dwgs.User" user "User.Drawings")
		(19 "Cmts.User" user "User.Comments")
		(21 "Eco1.User" user "User.Eco1")
		(23 "Eco2.User" user "User.Eco2")
		(25 "Edge.Cuts" user "Board Geometry/Outline")
		(27 "Margin" user)
		(31 "F.CrtYd" user "Package Geometry/Place Bound Top")
		(29 "B.CrtYd" user "Package Geometry/Place Bound Bottom")
		(35 "F.Fab" user "Ref Des/Assembly Top")
		(33 "B.Fab" user "Ref Des/Assembly Bottom")
	)
	(footprint ""
		(layer "B.Cu")
		(at 17.145 -92.583 -90)
		(property "Reference" "R6W3"
			(at 0 0 90)
			(layer "B.SilkS")
			(hide yes)
			(effects
				(font
					(size 1.27 1.27)
				)
				(justify mirror)
			)
		)
		(property "Value" "*"
			(at -0.064008 -4.108196 270)
			(unlocked yes)
			(layer "B.Fab")
			(hide yes)
			(effects
				(font
					(size 1.27 1.016)
					(thickness 0.1524)
				)
				(justify mirror)
			)
		)
		(property "Device Type" "232KR2F-2-GP_SMD-RG1-232KR2F-2A"
			(at -0.064008 -5.632196 270)
			(unlocked yes)
			(layer "B.Fab")
			(hide yes)
			(effects
				(font
					(size 1.27 1.016)
					(thickness 0.1524)
				)
				(justify mirror)
			)
		)
		(duplicate_pad_numbers_are_jumpers no)
		(fp_line
			(start -0.508 -0.9398)
			(end 0.508 -0.9398)
			(stroke
				(width 0.1524)
				(type default)
			)
			(layer "B.SilkS")
		)
		(fp_line
			(start 0.508 -0.9398)
			(end 0.508 0.9398)
			(stroke
				(width 0.1524)
				(type default)
			)
			(layer "B.SilkS")
		)
		(fp_rect
			(start 0.508 0.9398)
			(end -0.508 -0.9398)
			(stroke
				(width 0)
				(type default)
			)
			(fill no)
			(layer "B.CrtYd")
		)
		(fp_rect
			(start 0.508 0.9398)
			(end -0.508 -0.9398)
			(stroke
				(width 0)
				(type default)
			)
			(fill no)
			(layer "B.Fab")
		)
		(pad "1" smd custom
			(at 0 -0.4445 90)
			(size 0.1397 0.1397)
			(layers "B.Cu" "B.Mask" "B.Paste")
			(net "UV_HIGH_SET_N")
			(options
				(clearance outline)
				(anchor circle)
			)
			(primitives
				(gr_poly
					(pts
						(arc
							(start -0.1778 0.2794)
							(mid -0.249642 0.249642)
							(end -0.2794 0.1778)
						)
						(arc
							(start -0.2794 -0.1778)
							(mid -0.249642 -0.249642)
							(end -0.1778 -0.2794)
						)
						(arc
							(start 0.1778 -0.2794)
							(mid 0.249642 -0.249642)
							(end 0.2794 -0.1778)
						)
						(arc
							(start 0.2794 0.1778)
							(mid 0.249642 0.249642)
							(end 0.1778 0.2794)
						)
					)
					(width 0)
					(fill yes)
				)
			)
		)
		(pad "2" smd custom
			(at 0 0.4445 90)
			(size 0.1397 0.1397)
			(layers "B.Cu" "B.Mask" "B.Paste")
			(net "A_P12V_STBY_FP_TRIGGER")
			(options
				(clearance outline)
				(anchor circle)
			)
			(primitives
				(gr_poly
					(pts
						(arc
							(start -0.1778 0.2794)
							(mid -0.249642 0.249642)
							(end -0.2794 0.1778)
						)
						(arc
							(start -0.2794 -0.1778)
							(mid -0.249642 -0.249642)
							(end -0.1778 -0.2794)
						)
						(arc
							(start 0.1778 -0.2794)
							(mid 0.249642 -0.249642)
							(end 0.2794 -0.1778)
						)
						(arc
							(start 0.2794 0.1778)
							(mid 0.249642 0.249642)
							(end 0.1778 0.2794)
						)
					)
					(width 0)
					(fill yes)
				)
			)
		)
	)
	(footprint ""
		(layer "B.Cu")
		(at 115.824 -70.739 -90)
		(property "Reference" "R7P21"
			(at 0 0 90)
			(layer "B.SilkS")
			(hide yes)
			(effects
				(font
					(size 1.27 1.27)
				)
				(justify mirror)
			)
		)
		(property "Value" ""
			(at 0 0 90)
			(layer "B.Fab")
			(effects
				(font
					(size 1.27 1.27)
				)
				(justify mirror)
			)
		)
		(duplicate_pad_numbers_are_jumpers no)
		(fp_poly
			(pts
				(xy 0.2794 -0.1016) (xy -0.2794 -0.1016) (xy -0.2794 0.9906) (xy 0.2794 0.9906)
			)
			(stroke
				(width 0)
				(type default)
			)
			(fill no)
			(layer "B.CrtYd")
		)
		(fp_line
			(start -0.2794 0.9906)
			(end -0.2794 -0.1016)
			(stroke
				(width 0.1)
				(type default)
			)
			(layer "B.Fab")
		)
		(fp_line
			(start 0.2794 0.9906)
			(end -0.2794 0.9906)
			(stroke
				(width 0.1)
				(type default)
			)
			(layer "B.Fab")
		)
		(fp_line
			(start -0.2794 -0.1016)
			(end 0.2794 -0.1016)
			(stroke
				(width 0.1)
				(type default)
			)
			(layer "B.Fab")
		)
		(fp_line
			(start 0.2794 -0.1016)
			(end 0.2794 0.9906)
			(stroke
				(width 0.1)
				(type default)
			)
			(layer "B.Fab")
		)
		(pad "1" smd rect
			(at 0 0 90)
			(size 0.508 0.508)
			(layers "B.Cu" "B.Mask" "B.Paste")
			(net "H_CPU1_MEMKLM_MEMHOT_G_N")
		)
		(pad "2" smd rect
			(at 0 0.889 90)
			(size 0.508 0.508)
			(layers "B.Cu" "B.Mask" "B.Paste")
			(net "PVCCIO_CPU1")
		)
		(zone
			(layer "B.Cu")
			(hatch none 0.5)
			(connect_pads
				(clearance 0)
			)
			(min_thickness 0.25)
			(keepout
				(tracks not_allowed)
				(vias allowed)
				(pads allowed)
				(copperpour not_allowed)
				(footprints allowed)
			)
			(placement
				(enabled no)
				(sheetname "")
			)
			(fill
				(thermal_gap 0.5)
				(thermal_bridge_width 0.5)
				(island_removal_mode 0)
			)
			(polygon
				(pts
					(xy 115.189 -70.485) (xy 115.189 -70.993) (xy 115.57 -70.993) (xy 115.57 -70.485)
				)
			)
		)
		(zone
			(layer "B.Cu")
			(hatch none 0.5)
			(connect_pads
				(clearance 0)
			)
			(min_thickness 0.25)
			(keepout
				(tracks allowed)
				(vias not_allowed)
				(pads allowed)
				(copperpour not_allowed)
				(footprints allowed)
			)
			(placement
				(enabled no)
				(sheetname "")
			)
			(fill
				(thermal_gap 0.5)
				(thermal_bridge_width 0.5)
				(island_removal_mode 0)
			)
			(polygon
				(pts
					(xy 115.57 -70.485) (xy 115.57 -70.993) (xy 115.189 -70.993) (xy 115.189 -70.485)
				)
			)
		)
	)
	(footprint ""
		(layer "B.Cu")
		(at 494.702084 -46.184312)
		(property "Reference" "R25W136"
			(at 0.8382 -0.67818 0)
			(unlocked yes)
			(layer "B.SilkS")
			(effects
				(font
					(size 0.4064 0.254)
					(thickness 0.1524)
				)
				(justify left mirror)
			)
		)
		(property "Value" ""
			(at 0 0 0)
			(layer "B.Fab")
			(effects
				(font
					(size 1.27 1.27)
				)
				(justify mirror)
			)
		)
		(duplicate_pad_numbers_are_jumpers no)
		(fp_poly
			(pts
				(xy 0.2794 -0.1016) (xy -0.2794 -0.1016) (xy -0.2794 0.9906) (xy 0.2794 0.9906)
			)
			(stroke
				(width 0)
				(type default)
			)
			(fill no)
			(layer "B.CrtYd")
		)
		(fp_line
			(start -0.2794 -0.1016)
			(end 0.2794 -0.1016)
			(stroke
				(width 0.1)
				(type default)
			)
			(layer "B.Fab")
		)
		(fp_line
			(start -0.2794 0.9906)
			(end -0.2794 -0.1016)
			(stroke
				(width 0.1)
				(type default)
			)
			(layer "B.Fab")
		)
		(fp_line
			(start 0.2794 -0.1016)
			(end 0.2794 0.9906)
			(stroke
				(width 0.1)
				(type default)
			)
			(layer "B.Fab")
		)
		(fp_line
			(start 0.2794 0.9906)
			(end -0.2794 0.9906)
			(stroke
				(width 0.1)
				(type default)
			)
			(layer "B.Fab")
		)
		(pad "1" smd rect
			(at 0 0 180)
			(size 0.508 0.508)
			(layers "B.Cu" "B.Mask" "B.Paste")
			(net "I2C_BMC_VGA_DDC_SDA_G")
		)
		(pad "2" smd rect
			(at 0 0.889 180)
			(size 0.508 0.508)
			(layers "B.Cu" "B.Mask" "B.Paste")
			(net "V_IBMC_5V_DDC_SDA_J")
		)
		(zone
			(layer "B.Cu")
			(hatch none 0.5)
			(connect_pads
				(clearance 0)
			)
			(min_thickness 0.25)
			(keepout
				(tracks allowed)
				(vias not_allowed)
				(pads allowed)
				(copperpour not_allowed)
				(footprints allowed)
			)
			(placement
				(enabled no)
				(sheetname "")
			)
			(fill
				(thermal_gap 0.5)
				(thermal_bridge_width 0.5)
				(island_removal_mode 0)
			)
			(polygon
				(pts
					(xy 494.956084 -45.930312) (xy 494.448084 -45.930312) (xy 494.448084 -45.549312) (xy 494.956084 -45.549312)
				)
			)
		)
		(zone
			(layer "B.Cu")
			(hatch none 0.5)
			(connect_pads
				(clearance 0)
			)
			(min_thickness 0.25)
			(keepout
				(tracks not_allowed)
				(vias allowed)
				(pads allowed)
				(copperpour not_allowed)
				(footprints allowed)
			)
			(placement
				(enabled no)
				(sheetname "")
			)
			(fill
				(thermal_gap 0.5)
				(thermal_bridge_width 0.5)
				(island_removal_mode 0)
			)
			(polygon
				(pts
					(xy 494.956084 -45.549312) (xy 494.448084 -45.549312) (xy 494.448084 -45.930312) (xy 494.956084 -45.930312)
				)
			)
		)
	)
)
